(kicad_pcb
	(version 20260206)
	(generator "pcbnew")
	(generator_version "10.0")
	(general
		(thickness 1.6)
		(legacy_teardrops no)
	)
	(paper "A4")
	(title_block
		(title "Wiwynn_Tioga_Pass_MB.brd")
		(comment 1 "Tioga Pass / footprints 3601-3608 of 4770")
	)
	(layers
		(0 "F.Cu" signal "TOP")
		(4 "In1.Cu" signal "L2GND")
		(6 "In2.Cu" signal "L3")
		(8 "In3.Cu" signal "L4GND")
		(10 "In4.Cu" signal "L5")
		(12 "In5.Cu" signal "L6GND")
		(14 "In6.Cu" signal "L7VCC")
		(16 "In7.Cu" signal "L8VCC")
		(18 "In8.Cu" signal "L9GND")
		(20 "In9.Cu" signal "L10")
		(22 "In10.Cu" signal "L11GND")
		(24 "In11.Cu" signal "L12")
		(26 "In12.Cu" signal "L13GND")
		(2 "B.Cu" signal "BOTTOM")
		(9 "F.Adhes" user "F.Adhesive")
		(11 "B.Adhes" user "B.Adhesive")
		(13 "F.Paste" user "Package Geometry/Pastemask Top")
		(15 "B.Paste" user "Package Geometry/Pastemask Bottom")
		(5 "F.SilkS" user "Ref Des/Silkscreen Top")
		(7 "B.SilkS" user "Ref Des/Silkscreen Bottom")
		(1 "F.Mask" user "Board Geometry/Soldermask Top")
		(3 "B.Mask" user "Board Geometry/Soldermask Bottom")
		(17 "Dwgs.User" user "User.Drawings")
		(19 "Cmts.User" user "User.Comments")
		(21 "Eco1.User" user "User.Eco1")
		(23 "Eco2.User" user "User.Eco2")
		(25 "Edge.Cuts" user "Board Geometry/Outline")
		(27 "Margin" user)
		(31 "F.CrtYd" user "Package Geometry/Place Bound Top")
		(29 "B.CrtYd" user "Package Geometry/Place Bound Bottom")
		(35 "F.Fab" user "Ref Des/Assembly Top")
		(33 "B.Fab" user "Ref Des/Assembly Bottom")
	)
	(footprint ""
		(layer "B.Cu")
		(at 404.0378 -116.7765 180)
		(property "Reference" "C2M13"
			(at 0 0 0)
			(layer "B.SilkS")
			(hide yes)
			(effects
				(font
					(size 1.27 1.27)
				)
				(justify mirror)
			)
		)
		(property "Value" ""
			(at 0 0 0)
			(layer "B.Fab")
			(effects
				(font
					(size 1.27 1.27)
				)
				(justify mirror)
			)
		)
		(duplicate_pad_numbers_are_jumpers no)
		(fp_poly
			(pts
				(xy 0.4953 -0.2032) (xy -0.4953 -0.2032) (xy -0.4953 1.6002) (xy 0.4953 1.6002)
			)
			(stroke
				(width 0)
				(type default)
			)
			(fill no)
			(layer "B.CrtYd")
		)
		(fp_line
			(start 0.4953 1.6002)
			(end 0.4953 -0.2032)
			(stroke
				(width 0.1)
				(type default)
			)
			(layer "B.Fab")
		)
		(fp_line
			(start 0.4953 -0.2032)
			(end -0.4953 -0.2032)
			(stroke
				(width 0.1)
				(type default)
			)
			(layer "B.Fab")
		)
		(fp_line
			(start -0.4953 1.6002)
			(end 0.4953 1.6002)
			(stroke
				(width 0.1)
				(type default)
			)
			(layer "B.Fab")
		)
		(fp_line
			(start -0.4953 -0.2032)
			(end -0.4953 1.6002)
			(stroke
				(width 0.1)
				(type default)
			)
			(layer "B.Fab")
		)
		(pad "1" smd rect
			(at 0 0)
			(size 0.762 0.889)
			(layers "B.Cu" "B.Mask" "B.Paste")
			(net "P1V05_PCH_STBY")
		)
		(pad "2" smd rect
			(at 0 1.397)
			(size 0.762 0.889)
			(layers "B.Cu" "B.Mask" "B.Paste")
			(net "GND")
		)
		(zone
			(layer "B.Cu")
			(hatch none 0.5)
			(connect_pads
				(clearance 0)
			)
			(min_thickness 0.25)
			(keepout
				(tracks not_allowed)
				(vias allowed)
				(pads allowed)
				(copperpour not_allowed)
				(footprints allowed)
			)
			(placement
				(enabled no)
				(sheetname "")
			)
			(fill
				(thermal_gap 0.5)
				(thermal_bridge_width 0.5)
				(island_removal_mode 0)
			)
			(polygon
				(pts
					(xy 403.6568 -117.221) (xy 404.4188 -117.221) (xy 404.4188 -117.729) (xy 403.6568 -117.729)
				)
			)
		)
	)
	(footprint ""
		(layer "B.Cu")
		(at 164.973 -66.3702 90)
		(property "Reference" "R6P41"
			(at 0 0 90)
			(layer "B.SilkS")
			(hide yes)
			(effects
				(font
					(size 1.27 1.27)
				)
				(justify mirror)
			)
		)
		(property "Value" ""
			(at 0 0 90)
			(layer "B.Fab")
			(effects
				(font
					(size 1.27 1.27)
				)
				(justify mirror)
			)
		)
		(duplicate_pad_numbers_are_jumpers no)
		(fp_poly
			(pts
				(xy 0.2794 -0.1016) (xy -0.2794 -0.1016) (xy -0.2794 0.9906) (xy 0.2794 0.9906)
			)
			(stroke
				(width 0)
				(type default)
			)
			(fill no)
			(layer "B.CrtYd")
		)
		(fp_line
			(start 0.2794 -0.1016)
			(end 0.2794 0.9906)
			(stroke
				(width 0.1)
				(type default)
			)
			(layer "B.Fab")
		)
		(fp_line
			(start -0.2794 -0.1016)
			(end 0.2794 -0.1016)
			(stroke
				(width 0.1)
				(type default)
			)
			(layer "B.Fab")
		)
		(fp_line
			(start 0.2794 0.9906)
			(end -0.2794 0.9906)
			(stroke
				(width 0.1)
				(type default)
			)
			(layer "B.Fab")
		)
		(fp_line
			(start -0.2794 0.9906)
			(end -0.2794 -0.1016)
			(stroke
				(width 0.1)
				(type default)
			)
			(layer "B.Fab")
		)
		(pad "1" smd rect
			(at 0 0 270)
			(size 0.508 0.508)
			(layers "B.Cu" "B.Mask" "B.Paste")
			(net "FM_PVCCIO_CPU1_EN")
		)
		(pad "2" smd rect
			(at 0 0.889 270)
			(size 0.508 0.508)
			(layers "B.Cu" "B.Mask" "B.Paste")
			(net "VR_PVCCIO_CPU1_EN")
		)
		(zone
			(layer "B.Cu")
			(hatch none 0.5)
			(connect_pads
				(clearance 0)
			)
			(min_thickness 0.25)
			(keepout
				(tracks allowed)
				(vias not_allowed)
				(pads allowed)
				(copperpour not_allowed)
				(footprints allowed)
			)
			(placement
				(enabled no)
				(sheetname "")
			)
			(fill
				(thermal_gap 0.5)
				(thermal_bridge_width 0.5)
				(island_removal_mode 0)
			)
			(polygon
				(pts
					(xy 165.227 -66.6242) (xy 165.227 -66.1162) (xy 165.608 -66.1162) (xy 165.608 -66.6242)
				)
			)
		)
		(zone
			(layer "B.Cu")
			(hatch none 0.5)
			(connect_pads
				(clearance 0)
			)
			(min_thickness 0.25)
			(keepout
				(tracks not_allowed)
				(vias allowed)
				(pads allowed)
				(copperpour not_allowed)
				(footprints allowed)
			)
			(placement
				(enabled no)
				(sheetname "")
			)
			(fill
				(thermal_gap 0.5)
				(thermal_bridge_width 0.5)
				(island_removal_mode 0)
			)
			(polygon
				(pts
					(xy 165.608 -66.6242) (xy 165.608 -66.1162) (xy 165.227 -66.1162) (xy 165.227 -66.6242)
				)
			)
		)
	)
	(footprint ""
		(layer "B.Cu")
		(at 274.066 3.81 90)
		(property "Reference" "C5U13"
			(at 0 0 90)
			(layer "B.SilkS")
			(hide yes)
			(effects
				(font
					(size 1.27 1.27)
				)
				(justify mirror)
			)
		)
		(property "Value" ""
			(at 0 0 90)
			(layer "B.Fab")
			(effects
				(font
					(size 1.27 1.27)
				)
				(justify mirror)
			)
		)
		(duplicate_pad_numbers_are_jumpers no)
		(fp_rect
			(start -0.7239 -0.2159)
			(end 0.7239 1.9939)
			(stroke
				(width 0)
				(type default)
			)
			(fill no)
			(layer "B.CrtYd")
		)
		(fp_line
			(start 0.7239 -0.2159)
			(end 0.7239 1.9939)
			(stroke
				(width 0.1)
				(type default)
			)
			(layer "B.Fab")
		)
		(fp_line
			(start -0.7239 -0.2159)
			(end 0.7239 -0.2159)
			(stroke
				(width 0.1)
				(type default)
			)
			(layer "B.Fab")
		)
		(fp_line
			(start 0.7239 1.9939)
			(end -0.7239 1.9939)
			(stroke
				(width 0.1)
				(type default)
			)
			(layer "B.Fab")
		)
		(fp_line
			(start -0.7239 1.9939)
			(end -0.7239 -0.2159)
			(stroke
				(width 0.1)
				(type default)
			)
			(layer "B.Fab")
		)
		(pad "1" smd rect
			(at 0 0 270)
			(size 1.27 1.016)
			(layers "B.Cu" "B.Mask" "B.Paste")
			(net "PVDDQ_ABC")
		)
		(pad "2" smd rect
			(at 0 1.778 270)
			(size 1.27 1.016)
			(layers "B.Cu" "B.Mask" "B.Paste")
			(net "GND")
		)
		(zone
			(layer "B.Cu")
			(hatch none 0.5)
			(connect_pads
				(clearance 0)
			)
			(min_thickness 0.25)
			(keepout
				(tracks not_allowed)
				(vias allowed)
				(pads allowed)
				(copperpour not_allowed)
				(footprints allowed)
			)
			(placement
				(enabled no)
				(sheetname "")
			)
			(fill
				(thermal_gap 0.5)
				(thermal_bridge_width 0.5)
				(island_removal_mode 0)
			)
			(polygon
				(pts
					(xy 274.574 4.445) (xy 275.336 4.445) (xy 275.336 3.175) (xy 274.574 3.175)
				)
			)
		)
	)
	(footprint ""
		(layer "B.Cu")
		(at 172.6692 -135.636)
		(property "Reference" "C6L12"
			(at 0 0 0)
			(layer "B.SilkS")
			(hide yes)
			(effects
				(font
					(size 1.27 1.27)
				)
				(justify mirror)
			)
		)
		(property "Value" ""
			(at 0 0 0)
			(layer "B.Fab")
			(effects
				(font
					(size 1.27 1.27)
				)
				(justify mirror)
			)
		)
		(duplicate_pad_numbers_are_jumpers no)
		(fp_poly
			(pts
				(xy 0.4953 -0.2032) (xy -0.4953 -0.2032) (xy -0.4953 1.6002) (xy 0.4953 1.6002)
			)
			(stroke
				(width 0)
				(type default)
			)
			(fill no)
			(layer "B.CrtYd")
		)
		(fp_line
			(start -0.4953 -0.2032)
			(end -0.4953 1.6002)
			(stroke
				(width 0.1)
				(type default)
			)
			(layer "B.Fab")
		)
		(fp_line
			(start -0.4953 1.6002)
			(end 0.4953 1.6002)
			(stroke
				(width 0.1)
				(type default)
			)
			(layer "B.Fab")
		)
		(fp_line
			(start 0.4953 -0.2032)
			(end -0.4953 -0.2032)
			(stroke
				(width 0.1)
				(type default)
			)
			(layer "B.Fab")
		)
		(fp_line
			(start 0.4953 1.6002)
			(end 0.4953 -0.2032)
			(stroke
				(width 0.1)
				(type default)
			)
			(layer "B.Fab")
		)
		(pad "1" smd rect
			(at 0 0 180)
			(size 0.762 0.889)
			(layers "B.Cu" "B.Mask" "B.Paste")
			(net "VR_VB_PVPP_KLM")
		)
		(pad "2" smd rect
			(at 0 1.397 180)
			(size 0.762 0.889)
			(layers "B.Cu" "B.Mask" "B.Paste")
			(net "AGND_PVPP_KLM")
		)
		(zone
			(layer "B.Cu")
			(hatch none 0.5)
			(connect_pads
				(clearance 0)
			)
			(min_thickness 0.25)
			(keepout
				(tracks not_allowed)
				(vias allowed)
				(pads allowed)
				(copperpour not_allowed)
				(footprints allowed)
			)
			(placement
				(enabled no)
				(sheetname "")
			)
			(fill
				(thermal_gap 0.5)
				(thermal_bridge_width 0.5)
				(island_removal_mode 0)
			)
			(polygon
				(pts
					(xy 173.0502 -135.1915) (xy 172.2882 -135.1915) (xy 172.2882 -134.6835) (xy 173.0502 -134.6835)
				)
			)
		)
	)
	(footprint ""
		(layer "B.Cu")
		(at 169.037 -4.699 90)
		(property "Reference" "C6U13"
			(at 0 0 90)
			(layer "B.SilkS")
			(hide yes)
			(effects
				(font
					(size 1.27 1.27)
				)
				(justify mirror)
			)
		)
		(property "Value" ""
			(at 0 0 90)
			(layer "B.Fab")
			(effects
				(font
					(size 1.27 1.27)
				)
				(justify mirror)
			)
		)
		(duplicate_pad_numbers_are_jumpers no)
		(fp_rect
			(start 0.4953 1.6002)
			(end -0.4953 -0.2032)
			(stroke
				(width 0)
				(type default)
			)
			(fill no)
			(layer "B.CrtYd")
		)
		(fp_line
			(start 0.4953 -0.2032)
			(end -0.4953 -0.2032)
			(stroke
				(width 0.1)
				(type default)
			)
			(layer "B.Fab")
		)
		(fp_line
			(start -0.4953 -0.2032)
			(end -0.4953 1.6002)
			(stroke
				(width 0.1)
				(type default)
			)
			(layer "B.Fab")
		)
		(fp_line
			(start 0.4953 1.6002)
			(end 0.4953 -0.2032)
			(stroke
				(width 0.1)
				(type default)
			)
			(layer "B.Fab")
		)
		(fp_line
			(start -0.4953 1.6002)
			(end 0.4953 1.6002)
			(stroke
				(width 0.1)
				(type default)
			)
			(layer "B.Fab")
		)
		(pad "1" smd rect
			(at 0 0 270)
			(size 0.762 0.889)
			(layers "B.Cu" "B.Mask" "B.Paste")
			(net "PVDDQ_GHJ")
		)
		(pad "2" smd rect
			(at 0 1.397 270)
			(size 0.762 0.889)
			(layers "B.Cu" "B.Mask" "B.Paste")
			(net "GND")
		)
		(zone
			(layer "B.Cu")
			(hatch none 0.5)
			(connect_pads
				(clearance 0)
			)
			(min_thickness 0.25)
			(keepout
				(tracks not_allowed)
				(vias allowed)
				(pads allowed)
				(copperpour not_allowed)
				(footprints allowed)
			)
			(placement
				(enabled no)
				(sheetname "")
			)
			(fill
				(thermal_gap 0.5)
				(thermal_bridge_width 0.5)
				(island_removal_mode 0)
			)
			(polygon
				(pts
					(xy 169.9895 -5.08) (xy 169.4815 -5.08) (xy 169.4815 -4.318) (xy 169.9895 -4.318)
				)
			)
		)
	)
	(footprint ""
		(layer "B.Cu")
		(at 498.487954 -47.771812)
		(property "Reference" "CR25W2"
			(at 1.495806 -1.067816 0)
			(unlocked yes)
			(layer "B.SilkS")
			(effects
				(font
					(size 0.4064 0.254)
					(thickness 0.1524)
				)
				(justify left mirror)
			)
		)
		(property "Value" ""
			(at 0 0 0)
			(layer "B.Fab")
			(effects
				(font
					(size 1.27 1.27)
				)
				(justify mirror)
			)
		)
		(duplicate_pad_numbers_are_jumpers no)
		(fp_circle
			(center 0.589026 -0.5334)
			(end 0.716026 -0.5334)
			(stroke
				(width 0.254)
				(type default)
			)
			(fill no)
			(layer "B.SilkS")
		)
		(fp_rect
			(start 0.225552 2.167382)
			(end -0.809498 -0.167386)
			(stroke
				(width 0)
				(type default)
			)
			(fill no)
			(layer "B.CrtYd")
		)
		(fp_line
			(start -0.809498 -0.167386)
			(end -0.809498 2.167382)
			(stroke
				(width 0.1)
				(type default)
			)
			(layer "B.Fab")
		)
		(fp_line
			(start -0.809498 2.167382)
			(end 0.225552 2.167382)
			(stroke
				(width 0.1)
				(type default)
			)
			(layer "B.Fab")
		)
		(fp_line
			(start 0.225552 -0.167386)
			(end -0.809498 -0.167386)
			(stroke
				(width 0.1)
				(type default)
			)
			(layer "B.Fab")
		)
		(fp_line
			(start 0.225552 2.167382)
			(end 0.225552 -0.167386)
			(stroke
				(width 0.1)
				(type default)
			)
			(layer "B.Fab")
		)
		(fp_circle
			(center 0.589026 -0.5334)
			(end 0.716026 -0.5334)
			(stroke
				(width 0.254)
				(type default)
			)
			(fill no)
			(layer "B.Fab")
		)
		(pad "1" smd rect
			(at 0 0 180)
			(size 0.3556 0.2032)
			(layers "B.Cu" "B.Mask" "B.Paste")
			(net "V_IBMC_5V_DDC_SDA_J")
		)
		(pad "2" smd rect
			(at 0 0.500126 180)
			(size 0.3556 0.2032)
			(layers "B.Cu" "B.Mask" "B.Paste")
			(net "V_IBMC_5V_DDC_SCL_J")
		)
		(pad "3" smd rect
			(at -0.2921 0.999998 180)
			(size 0.9398 0.4064)
			(layers "B.Cu" "B.Mask" "B.Paste")
			(net "GND")
		)
		(pad "4" smd rect
			(at 0 1.500124 180)
			(size 0.3556 0.2032)
			(layers "B.Cu" "B.Mask" "B.Paste")
			(net "V_IO_VSYNC_J")
		)
		(pad "5" smd rect
			(at 0 1.999996 180)
			(size 0.3556 0.2032)
			(layers "B.Cu" "B.Mask" "B.Paste")
			(net "V_IO_HSYNC_J")
		)
		(pad "6" smd rect
			(at -0.583946 1.999996 180)
			(size 0.3556 0.2032)
			(layers "B.Cu" "B.Mask" "B.Paste")
			(net "V_IO_HSYNC_J")
		)
		(pad "7" smd rect
			(at -0.583946 1.500124 180)
			(size 0.3556 0.2032)
			(layers "B.Cu" "B.Mask" "B.Paste")
			(net "V_IO_VSYNC_J")
		)
		(pad "8" smd rect
			(at -0.583946 0.500126 180)
			(size 0.3556 0.2032)
			(layers "B.Cu" "B.Mask" "B.Paste")
			(net "V_IBMC_5V_DDC_SCL_J")
		)
		(pad "9" smd rect
			(at -0.583946 0 180)
			(size 0.3556 0.2032)
			(layers "B.Cu" "B.Mask" "B.Paste")
			(net "V_IBMC_5V_DDC_SDA_J")
		)
	)
	(footprint ""
		(layer "B.Cu")
		(at 363.032294 -145.471642)
		(property "Reference" "C7W7"
			(at 0 0 0)
			(layer "B.SilkS")
			(hide yes)
			(effects
				(font
					(size 1.27 1.27)
				)
				(justify mirror)
			)
		)
		(property "Value" "*"
			(at 0.0762 -6.2357 0)
			(unlocked yes)
			(layer "B.Fab")
			(hide yes)
			(effects
				(font
					(size 1.27 1.016)
					(thickness 0.1524)
				)
				(justify mirror)
			)
		)
		(property "Device Type" "SC22U16V5MX-4-GP_SMD-BCG5-SC22A"
			(at 0.0762 -8.2677 0)
			(unlocked yes)
			(layer "B.Fab")
			(hide yes)
			(effects
				(font
					(size 1.27 1.016)
					(thickness 0.1524)
				)
				(justify mirror)
			)
		)
		(duplicate_pad_numbers_are_jumpers no)
		(fp_line
			(start -0.635 0)
			(end 0.635 0)
			(stroke
				(width 0.508)
				(type default)
			)
			(layer "B.SilkS")
		)
		(fp_rect
			(start 0.9652 1.778)
			(end -0.9652 -1.778)
			(stroke
				(width 0)
				(type default)
			)
			(fill no)
			(layer "B.CrtYd")
		)
		(fp_poly
			(pts
				(xy 0.9652 -1.778) (xy -0.9652 -1.778) (xy -0.9652 1.778) (xy 0.9652 1.778)
			)
			(stroke
				(width 0)
				(type default)
			)
			(fill no)
			(layer "B.Fab")
		)
		(pad "1" smd rect
			(at 0 -0.9652 180)
			(size 1.397 1.143)
			(layers "B.Cu" "B.Mask" "B.Paste")
			(net "VR_FET_SW_P12V_STBY_PVDDQ_DEF")
		)
		(pad "2" smd rect
			(at 0 0.9652 180)
			(size 1.397 1.143)
			(layers "B.Cu" "B.Mask" "B.Paste")
			(net "GND")
		)
	)
	(footprint ""
		(layer "B.Cu")
		(at 393.0396 -37.1348 180)
		(property "Reference" "R2T18"
			(at 0 0 0)
			(layer "B.SilkS")
			(hide yes)
			(effects
				(font
					(size 1.27 1.27)
				)
				(justify mirror)
			)
		)
		(property "Value" ""
			(at 0 0 0)
			(layer "B.Fab")
			(effects
				(font
					(size 1.27 1.27)
				)
				(justify mirror)
			)
		)
		(duplicate_pad_numbers_are_jumpers no)
		(fp_poly
			(pts
				(xy 0.2794 -0.1016) (xy -0.2794 -0.1016) (xy -0.2794 0.9906) (xy 0.2794 0.9906)
			)
			(stroke
				(width 0)
				(type default)
			)
			(fill no)
			(layer "B.CrtYd")
		)
		(fp_line
			(start 0.2794 0.9906)
			(end -0.2794 0.9906)
			(stroke
				(width 0.1)
				(type default)
			)
			(layer "B.Fab")
		)
		(fp_line
			(start 0.2794 -0.1016)
			(end 0.2794 0.9906)
			(stroke
				(width 0.1)
				(type default)
			)
			(layer "B.Fab")
		)
		(fp_line
			(start -0.2794 0.9906)
			(end -0.2794 -0.1016)
			(stroke
				(width 0.1)
				(type default)
			)
			(layer "B.Fab")
		)
		(fp_line
			(start -0.2794 -0.1016)
			(end 0.2794 -0.1016)
			(stroke
				(width 0.1)
				(type default)
			)
			(layer "B.Fab")
		)
		(pad "1" smd rect
			(at 0 0)
			(size 0.508 0.508)
			(layers "B.Cu" "B.Mask" "B.Paste")
			(net "RST_BMC_SYSRST_BTN_OUT_B_R_N")
		)
		(pad "2" smd rect
			(at 0 0.889)
			(size 0.508 0.508)
			(layers "B.Cu" "B.Mask" "B.Paste")
			(net "RST_BMC_SYSRST_BTN_OUT_B_N")
		)
		(zone
			(layer "B.Cu")
			(hatch none 0.5)
			(connect_pads
				(clearance 0)
			)
			(min_thickness 0.25)
			(keepout
				(tracks not_allowed)
				(vias allowed)
				(pads allowed)
				(copperpour not_allowed)
				(footprints allowed)
			)
			(placement
				(enabled no)
				(sheetname "")
			)
			(fill
				(thermal_gap 0.5)
				(thermal_bridge_width 0.5)
				(island_removal_mode 0)
			)
			(polygon
				(pts
					(xy 392.7856 -37.7698) (xy 393.2936 -37.7698) (xy 393.2936 -37.3888) (xy 392.7856 -37.3888)
				)
			)
		)
		(zone
			(layer "B.Cu")
			(hatch none 0.5)
			(connect_pads
				(clearance 0)
			)
			(min_thickness 0.25)
			(keepout
				(tracks allowed)
				(vias not_allowed)
				(pads allowed)
				(copperpour not_allowed)
				(footprints allowed)
			)
			(placement
				(enabled no)
				(sheetname "")
			)
			(fill
				(thermal_gap 0.5)
				(thermal_bridge_width 0.5)
				(island_removal_mode 0)
			)
			(polygon
				(pts
					(xy 392.7856 -37.3888) (xy 393.2936 -37.3888) (xy 393.2936 -37.7698) (xy 392.7856 -37.7698)
				)
			)
		)
	)
)
